# T6G (Grand Teton) — schematic netlist excerpt (pin names and nets, part order shuffled) for the footprints in the layout excerpt that follows; sources: Cadence DE-HDL packaged netlist, KiCad conversion of 04192023_DAF0TMB3IC0_F0TG_MB_C_brd_V02_OCP.brd

C290  Q_CAP  0.1UF 10V 10% X7S  pkg C0201  page 334 : A = P0V9_CPU1_RT_2D ; B = GND
R4535  Q_RES  0 5% CHIP  pkg 0402LF  page 28 : A = CLK_100M_CPU0_CLK01_R_DP ; B = CLK_100M_CPU0_CLK01_DP
PC261  Q_CAP  22UF 4V 20% EMPTY  pkg C0805  page 209 : A = PVDD18_S5_P0 ; B = GND

(kicad_pcb
	(version 20260206)
	(generator "pcbnew")
	(generator_version "10.0")
	(general
		(thickness 1.6)
		(legacy_teardrops no)
	)
	(paper "A4")
	(title_block
		(title "04192023_DAF0TMB3IC0_F0TG_MB_C_brd_V02_OCP.brd")
		(comment 1 "Grand Teton / footprints 7120-7122 of 8354")
	)
	(layers
		(0 "F.Cu" signal "TOP")
		(4 "In1.Cu" signal "GND")
		(6 "In2.Cu" signal "IN1")
		(8 "In3.Cu" signal "GND1")
		(10 "In4.Cu" signal "IN2")
		(12 "In5.Cu" signal "GND2")
		(14 "In6.Cu" signal "IN3")
		(16 "In7.Cu" signal "GND3")
		(18 "In8.Cu" signal "VCC")
		(20 "In9.Cu" signal "VCC1")
		(22 "In10.Cu" signal "GND4")
		(24 "In11.Cu" signal "IN4")
		(26 "In12.Cu" signal "GND5")
		(28 "In13.Cu" signal "IN5")
		(30 "In14.Cu" signal "GND6")
		(32 "In15.Cu" signal "IN6")
		(34 "In16.Cu" signal "GND7")
		(2 "B.Cu" signal "BOTTOM")
		(9 "F.Adhes" user "F.Adhesive")
		(11 "B.Adhes" user "B.Adhesive")
		(13 "F.Paste" user "Package Geometry/Pastemask Top")
		(15 "B.Paste" user "Package Geometry/Pastemask Bottom")
		(5 "F.SilkS" user "Ref Des/Silkscreen Top")
		(7 "B.SilkS" user "Ref Des/Silkscreen Bottom")
		(1 "F.Mask" user "Board Geometry/Soldermask Top")
		(3 "B.Mask" user "Board Geometry/Soldermask Bottom")
		(17 "Dwgs.User" user "User.Drawings")
		(19 "Cmts.User" user "User.Comments")
		(21 "Eco1.User" user "User.Eco1")
		(23 "Eco2.User" user "User.Eco2")
		(25 "Edge.Cuts" user "Board Geometry/Outline")
		(27 "Margin" user)
		(31 "F.CrtYd" user "Package Geometry/Place Bound Top")
		(29 "B.CrtYd" user "Package Geometry/Place Bound Bottom")
		(35 "F.Fab" user "Ref Des/Assembly Top")
		(33 "B.Fab" user "Ref Des/Assembly Bottom")
	)
	(footprint ""
		(layer "B.Cu")
		(at 372.251986 -214.523828 90)
		(property "Reference" "R4535"
			(at 0 0 90)
			(layer "B.SilkS")
			(hide yes)
			(effects
				(font
					(size 1.27 1.27)
				)
				(justify mirror)
			)
		)
		(property "Value" ""
			(at 0 0 90)
			(layer "B.Fab")
			(effects
				(font
					(size 1.27 1.27)
				)
				(justify mirror)
			)
		)
		(duplicate_pad_numbers_are_jumpers no)
		(fp_line
			(start 0.512572 -0.4064)
			(end -0.351028 -0.4064)
			(stroke
				(width 0.1524)
				(type default)
			)
			(layer "B.SilkS")
		)
		(fp_line
			(start -0.7874 0.061214)
			(end -0.7874 0.4064)
			(stroke
				(width 0.1524)
				(type default)
			)
			(layer "B.SilkS")
		)
		(fp_line
			(start 0.7874 0.4064)
			(end 0.7874 0.061214)
			(stroke
				(width 0.1524)
				(type default)
			)
			(layer "B.SilkS")
		)
		(fp_line
			(start -0.7874 0.4064)
			(end 0.7874 0.4064)
			(stroke
				(width 0.1524)
				(type default)
			)
			(layer "B.SilkS")
		)
		(fp_line
			(start 0.67945 -0.305054)
			(end 0.12065 -0.305054)
			(stroke
				(width 0.1)
				(type default)
			)
			(layer "B.Fab")
		)
		(fp_line
			(start 0.12065 -0.305054)
			(end 0.12065 -0.2794)
			(stroke
				(width 0.1)
				(type default)
			)
			(layer "B.Fab")
		)
		(fp_line
			(start -0.12065 -0.3048)
			(end -0.67945 -0.3048)
			(stroke
				(width 0.1)
				(type default)
			)
			(layer "B.Fab")
		)
		(fp_line
			(start -0.67945 -0.3048)
			(end -0.67945 0.3048)
			(stroke
				(width 0.1)
				(type default)
			)
			(layer "B.Fab")
		)
		(fp_line
			(start 0.12065 -0.2794)
			(end -0.12065 -0.2794)
			(stroke
				(width 0.1)
				(type default)
			)
			(layer "B.Fab")
		)
		(fp_line
			(start -0.12065 -0.2794)
			(end -0.12065 -0.3048)
			(stroke
				(width 0.1)
				(type default)
			)
			(layer "B.Fab")
		)
		(fp_line
			(start 0.12065 0.2794)
			(end 0.12065 0.3048)
			(stroke
				(width 0.1)
				(type default)
			)
			(layer "B.Fab")
		)
		(fp_line
			(start -0.120396 0.2794)
			(end 0.12065 0.2794)
			(stroke
				(width 0.1)
				(type default)
			)
			(layer "B.Fab")
		)
		(fp_line
			(start 0.67945 0.3048)
			(end 0.67945 -0.305054)
			(stroke
				(width 0.1)
				(type default)
			)
			(layer "B.Fab")
		)
		(fp_line
			(start 0.12065 0.3048)
			(end 0.67945 0.3048)
			(stroke
				(width 0.1)
				(type default)
			)
			(layer "B.Fab")
		)
		(fp_line
			(start -0.120396 0.3048)
			(end -0.120396 0.2794)
			(stroke
				(width 0.1)
				(type default)
			)
			(layer "B.Fab")
		)
		(fp_line
			(start -0.67945 0.3048)
			(end -0.120396 0.3048)
			(stroke
				(width 0.1)
				(type default)
			)
			(layer "B.Fab")
		)
		(pad "1" smd circle
			(at 0.40005 0 270)
			(size 0 0)
			(layers "B.Cu" "B.Mask" "B.Paste")
			(net "CLK_100M_CPU0_CLK01_R_DP")
		)
		(pad "2" smd circle
			(at -0.40005 0 270)
			(size 0 0)
			(layers "B.Cu" "B.Mask" "B.Paste")
			(net "CLK_100M_CPU0_CLK01_DP")
		)
	)
	(footprint ""
		(layer "B.Cu")
		(at 336.279744 -154.256486 180)
		(property "Reference" "PC261"
			(at 0 0 0)
			(layer "B.SilkS")
			(hide yes)
			(effects
				(font
					(size 1.27 1.27)
				)
				(justify mirror)
			)
		)
		(property "Value" ""
			(at 0 0 0)
			(layer "B.Fab")
			(effects
				(font
					(size 1.27 1.27)
				)
				(justify mirror)
			)
		)
		(duplicate_pad_numbers_are_jumpers no)
		(fp_line
			(start 1.524 0.762)
			(end 1.524 -0.762)
			(stroke
				(width 0.1524)
				(type default)
			)
			(layer "B.SilkS")
		)
		(fp_line
			(start 1.524 -0.762)
			(end -1.524 -0.762)
			(stroke
				(width 0.1524)
				(type default)
			)
			(layer "B.SilkS")
		)
		(fp_line
			(start -1.524 0.762)
			(end 1.524 0.762)
			(stroke
				(width 0.1524)
				(type default)
			)
			(layer "B.SilkS")
		)
		(fp_line
			(start -1.524 -0.762)
			(end -1.524 0.762)
			(stroke
				(width 0.1524)
				(type default)
			)
			(layer "B.SilkS")
		)
		(fp_line
			(start 1.1049 0.724916)
			(end -1.1049 0.724916)
			(stroke
				(width 0.1)
				(type default)
			)
			(layer "B.Fab")
		)
		(fp_line
			(start 1.1049 -0.724916)
			(end 1.1049 0.724916)
			(stroke
				(width 0.1)
				(type default)
			)
			(layer "B.Fab")
		)
		(fp_line
			(start -1.1049 0.724916)
			(end -1.1049 -0.724916)
			(stroke
				(width 0.1)
				(type default)
			)
			(layer "B.Fab")
		)
		(fp_line
			(start -1.1049 -0.724916)
			(end 1.1049 -0.724916)
			(stroke
				(width 0.1)
				(type default)
			)
			(layer "B.Fab")
		)
		(pad "1" smd rect
			(at 0.889 0 180)
			(size 1.016 1.27)
			(layers "B.Cu" "B.Mask" "B.Paste")
			(net "PVDD18_S5_P0")
		)
		(pad "2" smd rect
			(at -0.889 0 180)
			(size 1.016 1.27)
			(layers "B.Cu" "B.Mask" "B.Paste")
			(net "GND")
		)
	)
	(footprint ""
		(layer "B.Cu")
		(at 86.04631 -388.011162 -90)
		(property "Reference" "C290"
			(at 0 0 90)
			(layer "B.SilkS")
			(hide yes)
			(effects
				(font
					(size 1.27 1.27)
				)
				(justify mirror)
			)
		)
		(property "Value" ""
			(at 0 0 90)
			(layer "B.Fab")
			(effects
				(font
					(size 1.27 1.27)
				)
				(justify mirror)
			)
		)
		(duplicate_pad_numbers_are_jumpers no)
		(fp_line
			(start -0.299974 0.150114)
			(end 0.299974 0.150114)
			(stroke
				(width 0.1)
				(type default)
			)
			(layer "B.Fab")
		)
		(fp_line
			(start 0.299974 0.150114)
			(end 0.299974 -0.150114)
			(stroke
				(width 0.1)
				(type default)
			)
			(layer "B.Fab")
		)
		(fp_line
			(start -0.299974 -0.150114)
			(end -0.299974 0.150114)
			(stroke
				(width 0.1)
				(type default)
			)
			(layer "B.Fab")
		)
		(fp_line
			(start 0.299974 -0.150114)
			(end -0.299974 -0.150114)
			(stroke
				(width 0.1)
				(type default)
			)
			(layer "B.Fab")
		)
		(pad "1" smd rect
			(at 0.2667 0 90)
			(size 0.3048 0.381)
			(layers "B.Cu" "B.Mask" "B.Paste")
			(net "P0V9_CPU1_RT_2D")
		)
		(pad "2" smd rect
			(at -0.2667 0 90)
			(size 0.3048 0.381)
			(layers "B.Cu" "B.Mask" "B.Paste")
			(net "GND")
		)
	)
)
